(kicad_pcb
	(version 20260206)
	(generator "pcbnew")
	(generator_version "10.0")
	(general
		(thickness 1.21888)
		(legacy_teardrops no)
	)
	(paper "A4")
	(title_block
		(title "timecard-v9 — TimeCard-DC-V9_EXP.PcbDoc")
		(comment 1 "Time Appliance Project (Time Card) / footprints 27-28 of 402")
	)
	(layers
		(0 "F.Cu" signal "TOP")
		(4 "In1.Cu" signal "SGND")
		(6 "In2.Cu" signal "IN1")
		(8 "In3.Cu" signal "IN2")
		(10 "In4.Cu" signal "SGND1")
		(2 "B.Cu" signal "BOTTOM")
		(9 "F.Adhes" user "F.Adhesive")
		(11 "B.Adhes" user "B.Adhesive")
		(13 "F.Paste" user "Top Paste")
		(15 "B.Paste" user "Bottom Paste")
		(5 "F.SilkS" user "Top Overlay")
		(7 "B.SilkS" user "Bottom Overlay")
		(1 "F.Mask" user "Top Solder")
		(3 "B.Mask" user "Bottom Solder")
		(17 "Dwgs.User" user "User.Drawings")
		(19 "Cmts.User" user "User.Comments")
		(21 "Eco1.User" user "User.Eco1")
		(23 "Eco2.User" user "User.Eco2")
		(25 "Edge.Cuts" user)
		(27 "Margin" user)
		(31 "F.CrtYd" user "Top Courtyard")
		(29 "B.CrtYd" user "Bottom Courtyard")
		(35 "F.Fab" user "Top Component Center")
		(33 "B.Fab" user "Bottom Component Center")
	)
	(footprint "FPGA_CONN:SingleFPGAConn"
		(locked yes)
		(layer "F.Cu")
		(at 151.29899 101.28552 -90)
		(property "Reference" "J35"
			(at -0.39436 -23.455129 270)
			(unlocked yes)
			(layer "F.SilkS")
			(effects
				(font
					(size 0.762 0.762)
					(thickness 0.2286)
				)
			)
		)
		(property "Value" "Single FPGA Conn"
			(at 9.25452 3.621231 270)
			(unlocked yes)
			(layer "F.SilkS")
			(hide yes)
			(effects
				(font
					(size 0.762 0.762)
					(thickness 0.2286)
				)
			)
		)
		(sheetname "07-FPGA")
		(sheetfile "07-FPGA.kicad_sch")
		(duplicate_pad_numbers_are_jumpers no)
		(fp_line
			(start -1.40005 1.24993)
			(end -1.40005 0.70002)
			(stroke
				(width 0.15011)
				(type solid)
			)
			(layer "F.SilkS")
		)
		(fp_line
			(start 1.40005 1.24993)
			(end -1.40005 1.24993)
			(stroke
				(width 0.15011)
				(type solid)
			)
			(layer "F.SilkS")
		)
		(fp_line
			(start 1.40005 1.24993)
			(end 2 0.70002)
			(stroke
				(width 0.15011)
				(type solid)
			)
			(layer "F.SilkS")
		)
		(fp_line
			(start -2 0.70002)
			(end -2 0.03302)
			(stroke
				(width 0.15011)
				(type solid)
			)
			(layer "F.SilkS")
		)
		(fp_line
			(start -1.40005 0.70002)
			(end -2 0.70002)
			(stroke
				(width 0.15011)
				(type solid)
			)
			(layer "F.SilkS")
		)
		(fp_line
			(start 2 0.70002)
			(end 2 0.03302)
			(stroke
				(width 0.15011)
				(type solid)
			)
			(layer "F.SilkS")
		)
		(fp_line
			(start -2 -20.03298)
			(end -2 -20.69998)
			(stroke
				(width 0.15011)
				(type solid)
			)
			(layer "F.SilkS")
		)
		(fp_line
			(start 2 -20.03298)
			(end 2 -20.69998)
			(stroke
				(width 0.15011)
				(type solid)
			)
			(layer "F.SilkS")
		)
		(fp_line
			(start -1.40005 -20.69998)
			(end -2 -20.69998)
			(stroke
				(width 0.15011)
				(type solid)
			)
			(layer "F.SilkS")
		)
		(fp_line
			(start -1.40005 -20.69998)
			(end -1.40005 -21.24989)
			(stroke
				(width 0.15011)
				(type solid)
			)
			(layer "F.SilkS")
		)
		(fp_line
			(start 2 -20.69998)
			(end 1.40005 -21.24989)
			(stroke
				(width 0.15011)
				(type solid)
			)
			(layer "F.SilkS")
		)
		(fp_line
			(start 1.40005 -21.24989)
			(end -1.40005 -21.24989)
			(stroke
				(width 0.15011)
				(type solid)
			)
			(layer "F.SilkS")
		)
		(fp_circle
			(center 3.5052 -0.22454)
			(end 3.30505 -0.22454)
			(stroke
				(width 0.40005)
				(type solid)
			)
			(fill no)
			(layer "F.SilkS")
		)
		(pad "1" smd rect
			(at 2.02489 -0.24994 270)
			(size 1.54991 0.24994)
			(layers "F.Cu" "F.Mask" "F.Paste")
			(net "GPS1_PIN15")
		)
		(pad "2" smd rect
			(at -2.02489 -0.24994 270)
			(size 1.54991 0.24994)
			(layers "F.Cu" "F.Mask" "F.Paste")
			(net "GPS1_PIN13")
		)
		(pad "3" smd rect
			(at 2.02489 -0.75006 270)
			(size 1.54991 0.24994)
			(layers "F.Cu" "F.Mask" "F.Paste")
			(net "GPS1_PIN14")
		)
		(pad "4" smd rect
			(at -2.02489 -0.75006 270)
			(size 1.54991 0.24994)
			(layers "F.Cu" "F.Mask" "F.Paste")
			(net "GPS1_PIN11")
		)
		(pad "5" smd rect
			(at 2.02489 -1.24993 270)
			(size 1.54991 0.24994)
			(layers "F.Cu" "F.Mask" "F.Paste")
			(net "GPS1_PIN12")
		)
		(pad "6" smd rect
			(at -2.02489 -1.24993 270)
			(size 1.54991 0.24994)
			(layers "F.Cu" "F.Mask" "F.Paste")
		)
		(pad "7" smd rect
			(at 2.02489 -1.75006 270)
			(size 1.54991 0.24994)
			(layers "F.Cu" "F.Mask" "F.Paste")
		)
		(pad "8" smd rect
			(at -2.02489 -1.75006 270)
			(size 1.54991 0.24994)
			(layers "F.Cu" "F.Mask" "F.Paste")
			(net "MAC_USB_PWR")
		)
		(pad "9" smd rect
			(at 2.02489 -2.24993 270)
			(size 1.54991 0.24994)
			(layers "F.Cu" "F.Mask" "F.Paste")
			(net "GND")
		)
		(pad "10" smd rect
			(at -2.02489 -2.24993 270)
			(size 1.54991 0.24994)
			(layers "F.Cu" "F.Mask" "F.Paste")
			(net "GND")
		)
		(pad "11" smd rect
			(at 2.02489 -2.75006 270)
			(size 1.54991 0.24994)
			(layers "F.Cu" "F.Mask" "F.Paste")
			(net "MAC_RF_OUT")
		)
		(pad "12" smd rect
			(at -2.02489 -2.75006 270)
			(size 1.54991 0.24994)
			(layers "F.Cu" "F.Mask" "F.Paste")
		)
		(pad "13" smd rect
			(at 2.02489 -3.24993 270)
			(size 1.54991 0.24994)
			(layers "F.Cu" "F.Mask" "F.Paste")
			(net "MAC_RF_OUT")
		)
		(pad "14" smd rect
			(at -2.02489 -3.24993 270)
			(size 1.54991 0.24994)
			(layers "F.Cu" "F.Mask" "F.Paste")
		)
		(pad "15" smd rect
			(at 2.02489 -3.75006 270)
			(size 1.54991 0.24994)
			(layers "F.Cu" "F.Mask" "F.Paste")
			(net "ANT1_OUT")
		)
		(pad "16" smd rect
			(at -2.02489 -3.75006 270)
			(size 1.54991 0.24994)
			(layers "F.Cu" "F.Mask" "F.Paste")
			(net "ANT3_IN")
		)
		(pad "17" smd rect
			(at 2.02489 -4.24993 270)
			(size 1.54991 0.24994)
			(layers "F.Cu" "F.Mask" "F.Paste")
			(net "ANT2_OUT")
		)
		(pad "18" smd rect
			(at -2.02489 -4.24993 270)
			(size 1.54991 0.24994)
			(layers "F.Cu" "F.Mask" "F.Paste")
			(net "ANT4_IN")
		)
		(pad "19" smd rect
			(at 2.02489 -4.75005 270)
			(size 1.54991 0.24994)
			(layers "F.Cu" "F.Mask" "F.Paste")
			(net "GND")
		)
		(pad "20" smd rect
			(at -2.02489 -4.75005 270)
			(size 1.54991 0.24994)
			(layers "F.Cu" "F.Mask" "F.Paste")
			(net "GND")
		)
		(pad "21" smd rect
			(at 2.02489 -5.24993 270)
			(size 1.54991 0.24994)
			(layers "F.Cu" "F.Mask" "F.Paste")
			(net "ANT1_IN")
		)
		(pad "22" smd rect
			(at -2.02489 -5.24993 270)
			(size 1.54991 0.24994)
			(layers "F.Cu" "F.Mask" "F.Paste")
		)
		(pad "23" smd rect
			(at 2.02489 -5.75005 270)
			(size 1.54991 0.24994)
			(layers "F.Cu" "F.Mask" "F.Paste")
			(net "ANT2_IN")
		)
		(pad "24" smd rect
			(at -2.02489 -5.75005 270)
			(size 1.54991 0.24994)
			(layers "F.Cu" "F.Mask" "F.Paste")
		)
		(pad "25" smd rect
			(at 2.02489 -6.24992 270)
			(size 1.54991 0.24994)
			(layers "F.Cu" "F.Mask" "F.Paste")
			(net "ANT3_OUT")
		)
		(pad "26" smd rect
			(at -2.02489 -6.24992 270)
			(size 1.54991 0.24994)
			(layers "F.Cu" "F.Mask" "F.Paste")
			(net "FPGA_MAC_UART_TX")
		)
		(pad "27" smd rect
			(at 2.02489 -6.75005 270)
			(size 1.54991 0.24994)
			(layers "F.Cu" "F.Mask" "F.Paste")
			(net "ANT4_OUT")
		)
		(pad "28" smd rect
			(at -2.02489 -6.75005 270)
			(size 1.54991 0.24994)
			(layers "F.Cu" "F.Mask" "F.Paste")
			(net "MAC_FPGA_UART_RX")
		)
		(pad "29" smd rect
			(at 2.02489 -7.24992 270)
			(size 1.54991 0.24994)
			(layers "F.Cu" "F.Mask" "F.Paste")
			(net "GND")
		)
		(pad "30" smd rect
			(at -2.02489 -7.24992 270)
			(size 1.54991 0.24994)
			(layers "F.Cu" "F.Mask" "F.Paste")
			(net "GND")
		)
		(pad "31" smd rect
			(at 2.02489 -7.75005 270)
			(size 1.54991 0.24994)
			(layers "F.Cu" "F.Mask" "F.Paste")
		)
		(pad "32" smd rect
			(at -2.02489 -7.75005 270)
			(size 1.54991 0.24994)
			(layers "F.Cu" "F.Mask" "F.Paste")
		)
		(pad "33" smd rect
			(at 2.02489 -8.24992 270)
			(size 1.54991 0.24994)
			(layers "F.Cu" "F.Mask" "F.Paste")
		)
		(pad "34" smd rect
			(at -2.02489 -8.24992 270)
			(size 1.54991 0.24994)
			(layers "F.Cu" "F.Mask" "F.Paste")
		)
		(pad "35" smd rect
			(at 2.02489 -8.75005 270)
			(size 1.54991 0.24994)
			(layers "F.Cu" "F.Mask" "F.Paste")
			(net "MAC_ALARM")
		)
		(pad "36" smd rect
			(at -2.02489 -8.75005 270)
			(size 1.54991 0.24994)
			(layers "F.Cu" "F.Mask" "F.Paste")
			(net "FPGA_BNO_XIN32")
		)
		(pad "37" smd rect
			(at 2.02489 -9.24992 270)
			(size 1.54991 0.24994)
			(layers "F.Cu" "F.Mask" "F.Paste")
			(net "MAC_BITE")
		)
		(pad "38" smd rect
			(at -2.02489 -9.24992 270)
			(size 1.54991 0.24994)
			(layers "F.Cu" "F.Mask" "F.Paste")
			(net "FPGA_BNO_XOUT32")
		)
		(pad "39" smd rect
			(at 2.02489 -9.75004 270)
			(size 1.54991 0.24994)
			(layers "F.Cu" "F.Mask" "F.Paste")
			(net "GND")
		)
		(pad "40" smd rect
			(at -2.02489 -9.75004 270)
			(size 1.54991 0.24994)
			(layers "F.Cu" "F.Mask" "F.Paste")
			(net "GND")
		)
		(pad "41" smd rect
			(at 2.02489 -10.24992 270)
			(size 1.54991 0.24994)
			(layers "F.Cu" "F.Mask" "F.Paste")
		)
		(pad "42" smd rect
			(at -2.02489 -10.24992 270)
			(size 1.54991 0.24994)
			(layers "F.Cu" "F.Mask" "F.Paste")
		)
		(pad "43" smd rect
			(at 2.02489 -10.75004 270)
			(size 1.54991 0.24994)
			(layers "F.Cu" "F.Mask" "F.Paste")
			(net "FPGA_MAC_PPS_OUT-")
		)
		(pad "44" smd rect
			(at -2.02489 -10.75004 270)
			(size 1.54991 0.24994)
			(layers "F.Cu" "F.Mask" "F.Paste")
		)
		(pad "45" smd rect
			(at 2.02489 -11.24991 270)
			(size 1.54991 0.24994)
			(layers "F.Cu" "F.Mask" "F.Paste")
		)
		(pad "46" smd rect
			(at -2.02489 -11.24991 270)
			(size 1.54991 0.24994)
			(layers "F.Cu" "F.Mask" "F.Paste")
		)
		(pad "47" smd rect
			(at 2.02489 -11.75004 270)
			(size 1.54991 0.24994)
			(layers "F.Cu" "F.Mask" "F.Paste")
			(net "FPGA_MAC_PPS_IN0-")
		)
		(pad "48" smd rect
			(at -2.02489 -11.75004 270)
			(size 1.54991 0.24994)
			(layers "F.Cu" "F.Mask" "F.Paste")
		)
		(pad "49" smd rect
			(at 2.02489 -12.24991 270)
			(size 1.54991 0.24994)
			(layers "F.Cu" "F.Mask" "F.Paste")
			(net "GND")
		)
		(pad "50" smd rect
			(at -2.02489 -12.24991 270)
			(size 1.54991 0.24994)
			(layers "F.Cu" "F.Mask" "F.Paste")
			(net "GND")
		)
		(pad "51" smd rect
			(at 2.02489 -12.75004 270)
			(size 1.54991 0.24994)
			(layers "F.Cu" "F.Mask" "F.Paste")
		)
		(pad "52" smd rect
			(at -2.02489 -12.75004 270)
			(size 1.54991 0.24994)
			(layers "F.Cu" "F.Mask" "F.Paste")
		)
		(pad "53" smd rect
			(at 2.02489 -13.24991 270)
			(size 1.54991 0.24994)
			(layers "F.Cu" "F.Mask" "F.Paste")
			(net "FPGA_MAC_PPS_IN1-")
		)
		(pad "54" smd rect
			(at -2.02489 -13.24991 270)
			(size 1.54991 0.24994)
			(layers "F.Cu" "F.Mask" "F.Paste")
		)
		(pad "55" smd rect
			(at 2.02489 -13.75004 270)
			(size 1.54991 0.24994)
			(layers "F.Cu" "F.Mask" "F.Paste")
		)
		(pad "56" smd rect
			(at -2.02489 -13.75004 270)
			(size 1.54991 0.24994)
			(layers "F.Cu" "F.Mask" "F.Paste")
		)
		(pad "57" smd rect
			(at 2.02489 -14.24991 270)
			(size 1.54991 0.24994)
			(layers "F.Cu" "F.Mask" "F.Paste")
		)
		(pad "58" smd rect
			(at -2.02489 -14.24991 270)
			(size 1.54991 0.24994)
			(layers "F.Cu" "F.Mask" "F.Paste")
		)
		(pad "59" smd rect
			(at 2.02489 -14.75003 270)
			(size 1.54991 0.24994)
			(layers "F.Cu" "F.Mask" "F.Paste")
			(net "GND")
		)
		(pad "60" smd rect
			(at -2.02489 -14.75003 270)
			(size 1.54991 0.24994)
			(layers "F.Cu" "F.Mask" "F.Paste")
			(net "GND")
		)
		(pad "61" smd rect
			(at 2.02489 -15.24991 270)
			(size 1.54991 0.24994)
			(layers "F.Cu" "F.Mask" "F.Paste")
			(net "SDA")
		)
		(pad "62" smd rect
			(at -2.02489 -15.24991 270)
			(size 1.54991 0.24994)
			(layers "F.Cu" "F.Mask" "F.Paste")
		)
		(pad "63" smd rect
			(at 2.02489 -15.75003 270)
			(size 1.54991 0.24994)
			(layers "F.Cu" "F.Mask" "F.Paste")
			(net "BNO_INT")
		)
		(pad "64" smd rect
			(at -2.02489 -15.75003 270)
			(size 1.54991 0.24994)
			(layers "F.Cu" "F.Mask" "F.Paste")
		)
		(pad "65" smd rect
			(at 2.02489 -16.2499 270)
			(size 1.54991 0.24994)
			(layers "F.Cu" "F.Mask" "F.Paste")
			(net "GPS2_PIN15")
		)
		(pad "66" smd rect
			(at -2.02489 -16.2499 270)
			(size 1.54991 0.24994)
			(layers "F.Cu" "F.Mask" "F.Paste")
		)
		(pad "67" smd rect
			(at 2.02489 -16.75003 270)
			(size 1.54991 0.24994)
			(layers "F.Cu" "F.Mask" "F.Paste")
			(net "SCL")
		)
		(pad "68" smd rect
			(at -2.02489 -16.75003 270)
			(size 1.54991 0.24994)
			(layers "F.Cu" "F.Mask" "F.Paste")
		)
		(pad "69" smd rect
			(at 2.02489 -17.2499 270)
			(size 1.54991 0.24994)
			(layers "F.Cu" "F.Mask" "F.Paste")
			(net "GND")
		)
		(pad "70" smd rect
			(at -2.02489 -17.2499 270)
			(size 1.54991 0.24994)
			(layers "F.Cu" "F.Mask" "F.Paste")
			(net "GND")
		)
		(pad "71" smd rect
			(at 2.02489 -17.75003 270)
			(size 1.54991 0.24994)
			(layers "F.Cu" "F.Mask" "F.Paste")
			(net "UART1_TXD")
		)
		(pad "72" smd rect
			(at -2.02489 -17.75003 270)
			(size 1.54991 0.24994)
			(layers "F.Cu" "F.Mask" "F.Paste")
			(net "MAC_USB+")
		)
		(pad "73" smd rect
			(at 2.02489 -18.2499 270)
			(size 1.54991 0.24994)
			(layers "F.Cu" "F.Mask" "F.Paste")
			(net "GPS2_PIN13")
		)
		(pad "74" smd rect
			(at -2.02489 -18.2499 270)
			(size 1.54991 0.24994)
			(layers "F.Cu" "F.Mask" "F.Paste")
			(net "MAC_USB-")
		)
		(pad "75" smd rect
			(at 2.02489 -18.75003 270)
			(size 1.54991 0.24994)
			(layers "F.Cu" "F.Mask" "F.Paste")
			(net "GPS2_PIN11")
		)
		(pad "76" smd rect
			(at -2.02489 -18.75003 270)
			(size 1.54991 0.24994)
			(layers "F.Cu" "F.Mask" "F.Paste")
			(net "GPS2_PIN12")
		)
		(pad "77" smd rect
			(at 2.02489 -19.2499 270)
			(size 1.54991 0.24994)
			(layers "F.Cu" "F.Mask" "F.Paste")
			(net "UART1_RXD")
		)
		(pad "78" smd rect
			(at -2.02489 -19.2499 270)
			(size 1.54991 0.24994)
			(layers "F.Cu" "F.Mask" "F.Paste")
			(net "GPS2_PIN14")
		)
		(pad "79" smd rect
			(at 2.02489 -19.75002 270)
			(size 1.54991 0.24994)
			(layers "F.Cu" "F.Mask" "F.Paste")
			(net "GPS1_RX")
		)
		(pad "80" smd rect
			(at -2.02489 -19.75002 270)
			(size 1.54991 0.24994)
			(layers "F.Cu" "F.Mask" "F.Paste")
			(net "GPS1_TX")
		)
		(pad "81" smd rect
			(at 0.01135 1.17626 270)
			(size 1.70002 1.35001)
			(layers "F.Cu" "F.Mask" "F.Paste")
		)
		(pad "82" thru_hole circle
			(at 0 0 270)
			(size 0.55016 0.55016)
			(drill 0.55016)
			(layers "*.Cu" "*.Mask")
			(remove_unused_layers no)
			(thermal_bridge_angle 90)
		)
		(pad "83" thru_hole circle
			(at 0 -19.99996 270)
			(size 0.55016 0.55016)
			(drill 0.55016)
			(layers "*.Cu" "*.Mask")
			(remove_unused_layers no)
			(thermal_bridge_angle 90)
		)
		(pad "84" smd rect
			(at 0.01135 -21.17374 270)
			(size 1.70002 1.35001)
			(layers "F.Cu" "F.Mask" "F.Paste")
		)
	)
	(footprint "GNSS:GNSS"
		(locked yes)
		(layer "F.Cu")
		(at 107.2491 70.7286)
		(property "Reference" "U9"
			(at -1.3275 4.294255 180)
			(unlocked yes)
			(layer "F.SilkS")
			(effects
				(font
					(size 0.762 0.762)
					(thickness 0.2286)
				)
				(justify left bottom)
			)
		)
		(property "Value" "RCB-F9T"
			(at -9.8007 23.073645 0)
			(unlocked yes)
			(layer "F.SilkS")
			(hide yes)
			(effects
				(font
					(size 0.762 0.762)
					(thickness 0.2286)
				)
				(justify left bottom)
			)
		)
		(sheetname "05-GPS_IMU_SENSORS")
		(sheetfile "05-GPS_IMU_SENSORS.kicad_sch")
		(duplicate_pad_numbers_are_jumpers no)
		(fp_line
			(start -6.11 -20.47)
			(end 61.07 -20.47)
			(stroke
				(width 0.254)
				(type solid)
			)
			(layer "F.SilkS")
		)
		(fp_line
			(start -6.11 11.28)
			(end -6.11 -20.47)
			(stroke
				(width 0.254)
				(type solid)
			)
			(layer "F.SilkS")
		)
		(fp_line
			(start -6.11 11.28)
			(end 61.07 11.28)
			(stroke
				(width 0.254)
				(type solid)
			)
			(layer "F.SilkS")
		)
		(fp_line
			(start 61.07 11.28)
			(end 61.07 -20.47)
			(stroke
				(width 0.254)
				(type solid)
			)
			(layer "F.SilkS")
		)
		(pad "0" thru_hole circle
			(at 0 -2 270)
			(size 0 0)
			(drill 0.76)
			(layers "*.Cu" "*.Mask")
			(remove_unused_layers no)
			(thermal_bridge_angle 90)
		)
		(pad "0" thru_hole circle
			(at 0 2 270)
			(size 0 0)
			(drill 0.76)
			(layers "*.Cu" "*.Mask")
			(remove_unused_layers no)
			(thermal_bridge_angle 90)
		)
		(pad "1" smd rect
			(at -2.2225 3 270)
			(size 1.12 2.105)
			(layers "F.Cu" "F.Mask" "F.Paste")
			(net "+5.0V")
		)
		(pad "2" smd rect
			(at 2.2225 3 270)
			(size 1.12 2.105)
			(layers "F.Cu" "F.Mask" "F.Paste")
			(net "+3.3V")
		)
		(pad "3" smd rect
			(at -2.2225 1 270)
			(size 1.12 2.105)
			(layers "F.Cu" "F.Mask" "F.Paste")
			(net "RCB_GPS1_TX")
		)
		(pad "4" smd rect
			(at 2.2225 1 270)
			(size 1.12 2.105)
			(layers "F.Cu" "F.Mask" "F.Paste")
			(net "GPS1_RST")
		)
		(pad "5" smd rect
			(at -2.2225 -1 270)
			(size 1.12 2.105)
			(layers "F.Cu" "F.Mask" "F.Paste")
			(net "RCB_GPS1_RX")
		)
		(pad "6" smd rect
			(at 2.2225 -1 270)
			(size 1.12 2.105)
			(layers "F.Cu" "F.Mask" "F.Paste")
			(net "RCB_GPS1_TP1")
		)
		(pad "7" smd rect
			(at -2.2225 -3 270)
			(size 1.12 2.105)
			(layers "F.Cu" "F.Mask" "F.Paste")
			(net "RCB_GPS1_TP2")
		)
		(pad "8" smd rect
			(at 2.2225 -3 270)
			(size 1.12 2.105)
			(layers "F.Cu" "F.Mask" "F.Paste")
			(net "GND")
		)
	)
)
